# BASEBOARD_FAB2 (Tioga Pass) — schematic netlist excerpt (pin names and nets, part order shuffled) for the footprints in the layout excerpt that follows; sources: Cadence DE-HDL packaged netlist, KiCad conversion of Wiwynn_Tioga_Pass_MB.brd

C9N15  CAP  0.22UF 16V 10% X7R  pkg 0402  page 182 : A = P3E_CPU1_PE3_MP_C_TXN<9> ; B = P3E_CPU1_PE3_MP_TXN<9>
C3U1  CAPP  470UF 2.5V 20% ALUM  pkg 3018  page 217 : A = PVDDQ_ABC ; B = GND
R3N20  RES  100.0 1% CHIP  pkg 0402  page 212 : A = VSENSE_PVCCIO_CPU0_AVSN ; B = GND

(kicad_pcb
	(version 20260206)
	(generator "pcbnew")
	(generator_version "10.0")
	(general
		(thickness 1.6)
		(legacy_teardrops no)
	)
	(paper "A4")
	(title_block
		(title "Wiwynn_Tioga_Pass_MB.brd")
		(comment 1 "Tioga Pass / footprints 4634-4636 of 4770")
	)
	(layers
		(0 "F.Cu" signal "TOP")
		(4 "In1.Cu" signal "L2GND")
		(6 "In2.Cu" signal "L3")
		(8 "In3.Cu" signal "L4GND")
		(10 "In4.Cu" signal "L5")
		(12 "In5.Cu" signal "L6GND")
		(14 "In6.Cu" signal "L7VCC")
		(16 "In7.Cu" signal "L8VCC")
		(18 "In8.Cu" signal "L9GND")
		(20 "In9.Cu" signal "L10")
		(22 "In10.Cu" signal "L11GND")
		(24 "In11.Cu" signal "L12")
		(26 "In12.Cu" signal "L13GND")
		(2 "B.Cu" signal "BOTTOM")
		(9 "F.Adhes" user "F.Adhesive")
		(11 "B.Adhes" user "B.Adhesive")
		(13 "F.Paste" user "Package Geometry/Pastemask Top")
		(15 "B.Paste" user "Package Geometry/Pastemask Bottom")
		(5 "F.SilkS" user "Ref Des/Silkscreen Top")
		(7 "B.SilkS" user "Ref Des/Silkscreen Bottom")
		(1 "F.Mask" user "Board Geometry/Soldermask Top")
		(3 "B.Mask" user "Board Geometry/Soldermask Bottom")
		(17 "Dwgs.User" user "User.Drawings")
		(19 "Cmts.User" user "User.Comments")
		(21 "Eco1.User" user "User.Eco1")
		(23 "Eco2.User" user "User.Eco2")
		(25 "Edge.Cuts" user "Board Geometry/Outline")
		(27 "Margin" user)
		(31 "F.CrtYd" user "Package Geometry/Place Bound Top")
		(29 "B.CrtYd" user "Package Geometry/Place Bound Bottom")
		(35 "F.Fab" user "Ref Des/Assembly Top")
		(33 "B.Fab" user "Ref Des/Assembly Bottom")
	)
	(footprint ""
		(layer "B.Cu")
		(at 353.367848 -89.98204 180)
		(property "Reference" "R3N20"
			(at 0 0 0)
			(layer "B.SilkS")
			(hide yes)
			(effects
				(font
					(size 1.27 1.27)
				)
				(justify mirror)
			)
		)
		(property "Value" ""
			(at 0 0 0)
			(layer "B.Fab")
			(effects
				(font
					(size 1.27 1.27)
				)
				(justify mirror)
			)
		)
		(duplicate_pad_numbers_are_jumpers no)
		(fp_poly
			(pts
				(xy 0.2794 -0.1016) (xy -0.2794 -0.1016) (xy -0.2794 0.9906) (xy 0.2794 0.9906)
			)
			(stroke
				(width 0)
				(type default)
			)
			(fill no)
			(layer "B.CrtYd")
		)
		(fp_line
			(start 0.2794 0.9906)
			(end -0.2794 0.9906)
			(stroke
				(width 0.1)
				(type default)
			)
			(layer "B.Fab")
		)
		(fp_line
			(start 0.2794 -0.1016)
			(end 0.2794 0.9906)
			(stroke
				(width 0.1)
				(type default)
			)
			(layer "B.Fab")
		)
		(fp_line
			(start -0.2794 0.9906)
			(end -0.2794 -0.1016)
			(stroke
				(width 0.1)
				(type default)
			)
			(layer "B.Fab")
		)
		(fp_line
			(start -0.2794 -0.1016)
			(end 0.2794 -0.1016)
			(stroke
				(width 0.1)
				(type default)
			)
			(layer "B.Fab")
		)
		(pad "1" smd rect
			(at 0 0)
			(size 0.508 0.508)
			(layers "B.Cu" "B.Mask" "B.Paste")
			(net "VSENSE_PVCCIO_CPU0_AVSN")
		)
		(pad "2" smd rect
			(at 0 0.889)
			(size 0.508 0.508)
			(layers "B.Cu" "B.Mask" "B.Paste")
			(net "GND")
		)
		(zone
			(layer "B.Cu")
			(hatch none 0.5)
			(connect_pads
				(clearance 0)
			)
			(min_thickness 0.25)
			(keepout
				(tracks not_allowed)
				(vias allowed)
				(pads allowed)
				(copperpour not_allowed)
				(footprints allowed)
			)
			(placement
				(enabled no)
				(sheetname "")
			)
			(fill
				(thermal_gap 0.5)
				(thermal_bridge_width 0.5)
				(island_removal_mode 0)
			)
			(polygon
				(pts
					(xy 353.113848 -90.61704) (xy 353.621848 -90.61704) (xy 353.621848 -90.23604) (xy 353.113848 -90.23604)
				)
			)
		)
		(zone
			(layer "B.Cu")
			(hatch none 0.5)
			(connect_pads
				(clearance 0)
			)
			(min_thickness 0.25)
			(keepout
				(tracks allowed)
				(vias not_allowed)
				(pads allowed)
				(copperpour not_allowed)
				(footprints allowed)
			)
			(placement
				(enabled no)
				(sheetname "")
			)
			(fill
				(thermal_gap 0.5)
				(thermal_bridge_width 0.5)
				(island_removal_mode 0)
			)
			(polygon
				(pts
					(xy 353.113848 -90.23604) (xy 353.621848 -90.23604) (xy 353.621848 -90.61704) (xy 353.113848 -90.61704)
				)
			)
		)
	)
	(footprint ""
		(layer "B.Cu")
		(at 17.83842 -99.71532 90)
		(property "Reference" "C9N15"
			(at 0 0 90)
			(layer "B.SilkS")
			(hide yes)
			(effects
				(font
					(size 1.27 1.27)
				)
				(justify mirror)
			)
		)
		(property "Value" ""
			(at 0 0 90)
			(layer "B.Fab")
			(effects
				(font
					(size 1.27 1.27)
				)
				(justify mirror)
			)
		)
		(duplicate_pad_numbers_are_jumpers no)
		(fp_poly
			(pts
				(xy -0.3048 -0.1016) (xy -0.3048 0.9906) (xy 0.3048 0.9906) (xy 0.3048 -0.1016)
			)
			(stroke
				(width 0)
				(type default)
			)
			(fill no)
			(layer "B.CrtYd")
		)
		(fp_line
			(start 0.3048 -0.1016)
			(end 0.3048 0.9906)
			(stroke
				(width 0.1)
				(type default)
			)
			(layer "B.Fab")
		)
		(fp_line
			(start -0.3048 -0.1016)
			(end 0.3048 -0.1016)
			(stroke
				(width 0.1)
				(type default)
			)
			(layer "B.Fab")
		)
		(fp_line
			(start 0.3048 0.9906)
			(end -0.3048 0.9906)
			(stroke
				(width 0.1)
				(type default)
			)
			(layer "B.Fab")
		)
		(fp_line
			(start -0.3048 0.9906)
			(end -0.3048 -0.1016)
			(stroke
				(width 0.1)
				(type default)
			)
			(layer "B.Fab")
		)
		(pad "1" smd rect
			(at 0 0 270)
			(size 0.508 0.508)
			(layers "B.Cu" "B.Mask" "B.Paste")
			(net "P3E_CPU1_PE3_MP_C_TXN<9>")
		)
		(pad "2" smd rect
			(at 0 0.889 270)
			(size 0.508 0.508)
			(layers "B.Cu" "B.Mask" "B.Paste")
			(net "P3E_CPU1_PE3_MP_TXN<9>")
		)
		(zone
			(layer "B.Cu")
			(hatch none 0.5)
			(connect_pads
				(clearance 0)
			)
			(min_thickness 0.25)
			(keepout
				(tracks allowed)
				(vias not_allowed)
				(pads allowed)
				(copperpour not_allowed)
				(footprints allowed)
			)
			(placement
				(enabled no)
				(sheetname "")
			)
			(fill
				(thermal_gap 0.5)
				(thermal_bridge_width 0.5)
				(island_removal_mode 0)
			)
			(polygon
				(pts
					(xy 18.09242 -99.96932) (xy 18.09242 -99.46132) (xy 18.47342 -99.46132) (xy 18.47342 -99.96932)
				)
			)
		)
		(zone
			(layer "B.Cu")
			(hatch none 0.5)
			(connect_pads
				(clearance 0)
			)
			(min_thickness 0.25)
			(keepout
				(tracks not_allowed)
				(vias allowed)
				(pads allowed)
				(copperpour not_allowed)
				(footprints allowed)
			)
			(placement
				(enabled no)
				(sheetname "")
			)
			(fill
				(thermal_gap 0.5)
				(thermal_bridge_width 0.5)
				(island_removal_mode 0)
			)
			(polygon
				(pts
					(xy 18.47342 -99.96932) (xy 18.47342 -99.46132) (xy 18.09242 -99.46132) (xy 18.09242 -99.96932)
				)
			)
		)
	)
	(footprint ""
		(layer "B.Cu")
		(at 334.518 -10.795 180)
		(property "Reference" "C3U1"
			(at -3.27533 3.683 270)
			(unlocked yes)
			(layer "B.SilkS")
			(effects
				(font
					(size 0.7874 0.5842)
					(thickness 0.1524)
				)
				(justify mirror)
			)
		)
		(property "Value" ""
			(at 0 0 0)
			(layer "B.Fab")
			(effects
				(font
					(size 1.27 1.27)
				)
				(justify mirror)
			)
		)
		(duplicate_pad_numbers_are_jumpers no)
		(fp_line
			(start 2.563114 1.633728)
			(end 1.6002 1.633728)
			(stroke
				(width 0.1524)
				(type default)
			)
			(layer "B.SilkS")
		)
		(fp_line
			(start 2.563114 -1.616456)
			(end 2.563114 1.633728)
			(stroke
				(width 0.1524)
				(type default)
			)
			(layer "B.SilkS")
		)
		(fp_line
			(start 2.286 7.366)
			(end 2.286 1.632712)
			(stroke
				(width 0.1524)
				(type default)
			)
			(layer "B.SilkS")
		)
		(fp_line
			(start 2.286 7.366)
			(end 1.60147 7.366)
			(stroke
				(width 0.1524)
				(type default)
			)
			(layer "B.SilkS")
		)
		(fp_line
			(start 1.6002 -1.616456)
			(end 2.563114 -1.616456)
			(stroke
				(width 0.1524)
				(type default)
			)
			(layer "B.SilkS")
		)
		(fp_line
			(start -1.6002 -1.616456)
			(end -2.504948 -1.616456)
			(stroke
				(width 0.1524)
				(type default)
			)
			(layer "B.SilkS")
		)
		(fp_line
			(start -2.286 7.366)
			(end -1.600708 7.366)
			(stroke
				(width 0.1524)
				(type default)
			)
			(layer "B.SilkS")
		)
		(fp_line
			(start -2.286 7.366)
			(end -2.286 1.63195)
			(stroke
				(width 0.1524)
				(type default)
			)
			(layer "B.SilkS")
		)
		(fp_line
			(start -2.504948 1.633728)
			(end -1.6002 1.633728)
			(stroke
				(width 0.1524)
				(type default)
			)
			(layer "B.SilkS")
		)
		(fp_line
			(start -2.504948 -1.616456)
			(end -2.504948 1.633728)
			(stroke
				(width 0.1524)
				(type default)
			)
			(layer "B.SilkS")
		)
		(fp_rect
			(start -2.286 -0.254)
			(end 2.286 7.366)
			(stroke
				(width 0)
				(type default)
			)
			(fill no)
			(layer "B.CrtYd")
		)
		(fp_line
			(start 2.286 7.366)
			(end 2.286 -0.254)
			(stroke
				(width 0.1)
				(type default)
			)
			(layer "B.Fab")
		)
		(fp_line
			(start 2.286 -0.254)
			(end -2.286 -0.254)
			(stroke
				(width 0.1)
				(type default)
			)
			(layer "B.Fab")
		)
		(fp_line
			(start -2.286 7.366)
			(end 2.286 7.366)
			(stroke
				(width 0.1)
				(type default)
			)
			(layer "B.Fab")
		)
		(fp_line
			(start -2.286 -0.254)
			(end -2.286 7.366)
			(stroke
				(width 0.1)
				(type default)
			)
			(layer "B.Fab")
		)
		(pad "1" smd rect
			(at 0 0)
			(size 2.54 3.048)
			(layers "B.Cu" "B.Mask" "B.Paste")
			(net "PVDDQ_ABC")
		)
		(pad "2" smd rect
			(at 0 7.112)
			(size 2.54 3.048)
			(layers "B.Cu" "B.Mask" "B.Paste")
			(net "GND")
		)
	)
)
